FILE_TYPE = CONNECTIVITY;
{Allegro Design Entry HDL 17.2-2016 S081 (4005846) 1/11/2022}
"PAGE_NUMBER" = 55;
0"NC";
1"P3V3_LDO\g";
2"P12V_AUX\g";
3"PVCC1_AUX\g";
4"PVCC1_AUX\g";
5"P5V_AUX\g";
6"PVCC1_AUX\g";
7"P3V3_AUX\g";
8"P1V2_AUX\g";
9"P3V3_AUX\g";
10"GND\g";
11"GND\g";
12"GND\g";
13"GND\g";
14"GND\g";
15"GND\g";
16"GND\g";
17"GND\g";
18"GND\g";
19"GND\g";
20"PWRGD_P3V3_RGM";
21"PWRGD_P1V2_AUX_R2";
22"PWRGD_P1V2_AUX";
23"P1V2_AUX_VCC";
24"PWRGD_P3V3_RGM_R3";
25"PWRGD_P1V8_AUX";
26"EN_P1V2_AUX";
27"SW_P1V2_AUX_FLT";
28"PWRGD_P5V_AUX";
29"EN_P1V2_AUX";
30"EN_P1V2_AUX_R";
31"SW_P1V2_AUX_SW";
32"PWRGD_P1V2_AUX_R";
33"SW_P1V2_AUX_BST";
34"P1V2_AUX_MODE";
%"UNIVERSAL_GND"
"1","(-2125,975)","0","logical_power","I10";
;
CDS_LIB"logical_power"
HDL_POWER"GND";
"A"13;
%"UNIVERSAL_GND"
"1","(-1225,-475)","0","logical_power","I14";
;
CDS_LIB"logical_power"
HDL_POWER"GND";
"A"18;
%"NB695GDZ"
"1","(-175,400)","0","pure_quanta","I15";
;
MATERIAL"IC"
PART_NUMBER"AL000695001"
PART_TYPE"SMLF"
VALUE"NB695GD-Z"
CDS_LIB"pure_quanta"
CDS_LMAN_SYM_OUTLINE"-250,725,250,-725"
NEEDS_NO_SIZE"TRUE"
LOCATION"PU41"
$SEC"1"
CDS_SEC"1";
"3V3"
$PN"10"23;
"SW"
$PN"8"31;
"VOUT"
$PN"12"8;
"MODE"
$PN"7"34;
"C0"
$PN"4"18;
"C1"
$PN"3"18;
"LP# \B"
$PN"6"23;
"AGND"
$PN"11"17;
"BST"
$PN"9"33;
"EN"
$PN"5"30;
"PGND"
$PN"2"17;
"PG"
$PN"13"32;
"VIN"
$PN"1"27;
%"Q_CAP"
"1","(-1175,1300)","0","pure_quanta","I16";
;
MATERIAL"X7R"
PART_NUMBER"CH4104K1B00"
TOLERANCE"10%"
VOLTAGE"25V"
PACK_TYPE"0402"
VALUE"0.1UF"
CDS_LIB"pure_quanta"
SEC_TYPE"0402"
LOCATION"PC253"
SEC"1";
"B"
$PN"2"13;
"A"
$PN"1"27;
%"UNIVERSAL_GND"
"1","(375,-525)","0","logical_power","I17";
;
CDS_LIB"logical_power"
HDL_POWER"GND";
"A"17;
%"Q_RES"
"2","(500,1350)","0","pure_quanta","I18";
;
TOLERANCE"1%"
WATTAGE"1/16W"
VALUE"10K"
PACK_TYPE"0402LF"
MATERIAL"CHIP"
PART_NUMBER"CS31002FB08"
CDS_LIB"pure_quanta"
SEC_TYPE"0402LF"
LOCATION"PR498"
SEC"1";
"A"
$PN"1"9;
"B"
$PN"2"32;
%"Q_CAP"
"1","(875,725)","0","pure_quanta","I19";
;
PACK_TYPE"0402"
MATERIAL"X7R"
VALUE"0.22UF"
VOLTAGE"16V"
TOLERANCE"10%"
PART_NUMBER"CH4223K1B00"
SEC_TYPE"0402"
CDS_LIB"pure_quanta"
LOCATION"PC254"
SEC"1";
"B"
$PN"2"31;
"A"
$PN"1"33;
%"VCCAUX15"
"1","(-3375,1900)","0","logical_power","I2";
;
HDL_POWER"P12V_AUX"
CDS_LIB"logical_power";
"A"2;
%"Q_INDUCTOR"
"1","(2125,600)","0","pure_quanta","I21";
;
MATERIAL"IND"
PART_NUMBER"CV-10B0MZ13"
VALUE"1UH"
PACK_TYPE"SMLF"
DCR"DCR=9MOHM"
NEEDS_NO_SIZE"TRUE"
CDS_LIB"pure_quanta"
LOCATION"PL31"
$SEC"1"
CDS_SEC"1";
"1"
$PN"1"31;
"2"
$PN"2"8;
%"Q_CAP"
"1","(2625,325)","0","pure_quanta","I23";
;
MATERIAL"X7R"
PART_NUMBER"CH4104K1B00"
VALUE"0.1UF"
TOLERANCE"10%"
VOLTAGE"25V"
PACK_TYPE"0402"
SEC_TYPE"0402"
CDS_LIB"pure_quanta"
LOCATION"PC255"
SEC"1";
"B"
$PN"2"16;
"A"
$PN"1"8;
%"Q_CAP"
"1","(3175,325)","0","pure_quanta","I24";
;
VALUE"22UF"
PACK_TYPE"0805"
VOLTAGE"4V"
MATERIAL"X6S"
TOLERANCE"20%"
PART_NUMBER"TMP_QCH622KMEA01"
CDS_LIB"pure_quanta"
SEC_TYPE"0805"
LOCATION"PC256"
SEC"1";
"B"
$PN"2"16;
"A"
$PN"1"8;
%"Q_CAP"
"1","(3425,325)","0","pure_quanta","I25";
;
MATERIAL"X6S"
VALUE"22UF"
TOLERANCE"20%"
VOLTAGE"4V"
PACK_TYPE"0805"
PART_NUMBER"TMP_QCH622KMEA01"
CDS_LIB"pure_quanta"
SEC_TYPE"0805"
LOCATION"PC257"
SEC"1";
"B"
$PN"2"16;
"A"
$PN"1"8;
%"UNIVERSAL_GND"
"1","(3925,0)","0","logical_power","I27";
;
CDS_LIB"logical_power"
HDL_POWER"GND";
"A"16;
%"Q_CAP"
"1","(3675,325)","0","pure_quanta","I28";
;
MATERIAL"X6S"
VALUE"22UF"
TOLERANCE"20%"
PACK_TYPE"0805"
VOLTAGE"4V"
PART_NUMBER"TMP_QCH622KMEA01"
CDS_LIB"pure_quanta"
SEC_TYPE"0805"
LOCATION"PC258"
SEC"1";
"B"
$PN"2"16;
"A"
$PN"1"8;
%"Q_CAP"
"1","(3925,325)","0","pure_quanta","I29";
;
PART_NUMBER"TMP_QCH622KMEA01"
PACK_TYPE"0805"
MATERIAL"X6S"
VALUE"22UF"
TOLERANCE"20%"
VOLTAGE"4V"
CDS_LIB"pure_quanta"
SEC_TYPE"0805"
LOCATION"PC259"
SEC"1";
"B"
$PN"2"16;
"A"
$PN"1"8;
%"VCCAUX15"
"1","(4575,700)","0","logical_power","I30";
;
HDL_POWER"P1V2_AUX"
CDS_LIB"logical_power";
"A"8;
%"Q_INDUCTOR"
"1","(-2775,1575)","0","pure_quanta","I31";
;
MATERIAL"IND"
PACK_TYPE"SMLF"
PART_NUMBER"CX220TN1001"
VALUE"BLM18SN220TN1D/8000MA"
NEEDS_NO_SIZE"TRUE"
CDS_LIB"pure_quanta"
LOCATION"PL29"
$SEC"1"
CDS_SEC"1";
"1"
$PN"1"2;
"2"
$PN"2"27;
%"VCCAUX15"
"1","(500,1625)","0","logical_power","I34";
;
HDL_POWER"P3V3_AUX"
CDS_LIB"logical_power";
"A"9;
%"Q_RES"
"1","(-1700,675)","0","pure_quanta","I38";
;
MATERIAL"CHIP"
VALUE"0"
PART_NUMBER"CS00002JB13"
PACK_TYPE"0402LF"
WATTAGE"1/16W"
TOLERANCE"5%"
CDS_LIB"pure_quanta"
LOCATION"R708"
$SEC"1"
CDS_SEC"1";
"B"
$PN"2"30;
"A"
$PN"1"26;
%"UNIVERSAL_GND"
"1","(-3575,-525)","0","logical_power","I4";
;
CDS_LIB"logical_power"
HDL_POWER"GND";
"A"14;
%"Q_RES"
"1","(-1700,575)","0","pure_quanta","I41";
;
MATERIAL"EMPTY"
VALUE"0"
PART_NUMBER"CS00002JB13"
PACK_TYPE"0402LF"
WATTAGE"1/16W"
TOLERANCE"5%"
CDS_LIB"pure_quanta"
LOCATION"R764"
$SEC"1"
CDS_SEC"1";
"B"
$PN"2"30;
"A"
$PN"1"25;
%"Q_CAP"
"1","(-2125,1300)","0","pure_quanta","I42";
;
PACK_TYPE"C0805"
VALUE"10UF"
TOLERANCE"10%"
PART_NUMBER"CH6104KEA00"
MATERIAL"X6S"
VOLTAGE"25V"
CDS_LIB"pure_quanta"
LOCATION"PC252"
$SEC"1"
CDS_SEC"1";
"B"
$PN"2"13;
"A"
$PN"1"27;
%"Q_CAP"
"1","(-1725,1300)","0","pure_quanta","I43";
;
PART_NUMBER"CH6104KEA00"
TOLERANCE"10%"
VOLTAGE"25V"
PACK_TYPE"C0805"
MATERIAL"X6S"
VALUE"10UF"
CDS_LIB"pure_quanta"
LOCATION"PC251"
$SEC"1"
CDS_SEC"1";
"B"
$PN"2"13;
"A"
$PN"1"27;
%"VCCAUX15"
"1","(-1900,-1100)","0","logical_power","I44";
;
HDL_POWER"P3V3_AUX"
CDS_LIB"logical_power";
"A"7;
%"Q_RES"
"1","(-1350,-1225)","0","pure_quanta","I45";
;
TOLERANCE"5%"
MATERIAL"CHIP"
VALUE"0"
WATTAGE"1/16W"
PACK_TYPE"0402LF"
PART_NUMBER"CS00002JB13"
CDS_LIB"pure_quanta"
LOCATION"PR274"
$SEC"1"
CDS_SEC"1";
"B"
$PN"2"6;
"A"
$PN"1"7;
%"VCCAUX15"
"1","(-625,-1075)","0","logical_power","I46";
;
HDL_POWER"PVCC1_AUX"
CDS_LIB"logical_power";
"A"6;
%"VCCAUX15"
"1","(-1900,-1450)","0","logical_power","I47";
;
HDL_POWER"P5V_AUX"
CDS_LIB"logical_power";
"A"5;
%"Q_RES"
"1","(-1350,-1550)","0","pure_quanta","I48";
;
PART_NUMBER"CS00002JB13"
VALUE"0"
TOLERANCE"5%"
MATERIAL"EMPTY"
WATTAGE"1/16W"
PACK_TYPE"0402LF"
CDS_LIB"pure_quanta"
LOCATION"PR275"
$SEC"1"
CDS_SEC"1";
"B"
$PN"2"4;
"A"
$PN"1"5;
%"VCCAUX15"
"1","(-625,-1400)","0","logical_power","I49";
;
HDL_POWER"PVCC1_AUX"
CDS_LIB"logical_power";
"A"4;
%"UNIVERSAL_GND"
"1","(-1050,-850)","0","logical_power","I5";
;
CDS_LIB"logical_power"
HDL_POWER"GND";
"A"15;
%"Q_RES"
"1","(1750,1075)","0","pure_quanta","I50";
;
PACK_TYPE"0402LF"
VALUE"0"
PART_NUMBER"CS00002JB13"
MATERIAL"CHIP"
WATTAGE"1/16W"
TOLERANCE"5%"
CDS_LIB"pure_quanta"
LOCATION"R276"
$SEC"1"
CDS_SEC"1";
"B"
$PN"2"22;
"A"
$PN"1"32;
%"UNIVERSAL_GND"
"1","(1325,675)","0","logical_power","I51";
;
CDS_LIB"logical_power"
HDL_POWER"GND";
"A"19;
%"Q_CAP"
"1","(1325,875)","0","pure_quanta","I52";
;
PACK_TYPE"C0402"
PART_NUMBER"CH30106KB19"
VALUE"0.001UF"
VOLTAGE"50V"
TOLERANCE"10%"
MATERIAL"EMPTY"
CDS_LIB"pure_quanta"
LOCATION"C155"
$SEC"1"
CDS_SEC"1";
"B"
$PN"2"19;
"A"
$PN"1"32;
%"UNIVERSAL_GND"
"1","(-3375,1175)","0","logical_power","I53";
;
HDL_POWER"GND"
CDS_LIB"logical_power";
"A"12;
%"Q_CAP"
"1","(-3375,1375)","0","pure_quanta","I54";
;
TOLERANCE"10%"
MATERIAL"X7R"
VALUE"0.1UF"
VOLTAGE"25V"
PACK_TYPE"0402"
PART_NUMBER"CH4104K1B00"
CDS_LIB"pure_quanta"
$LOCATION"C278"
CDS_LOCATION"C278"
$SEC"1"
CDS_SEC"1";
"B"
$PN"2"12;
"A"
$PN"1"2;
%"UNIVERSAL_GND"
"1","(-2050,2525)","0","logical_power","I57";
;
HDL_POWER"GND"
CDS_LIB"logical_power";
"A"11;
%"Q_RES"
"2","(-1050,-600)","0","pure_quanta","I6";
;
VALUE"150K"
TOLERANCE"1%"
WATTAGE"1/16W"
MATERIAL"CHIP"
PACK_TYPE"0402LF"
PART_NUMBER"CS41502FB04"
SEC_TYPE"0402LF"
CDS_LIB"pure_quanta"
LOCATION"PR496"
SEC"1";
"A"
$PN"1"34;
"B"
$PN"2"15;
%"UNIVERSAL_GND"
"1","(-1700,3225)","0","logical_power","I60";
;
HDL_POWER"GND"
CDS_LIB"logical_power";
"A"10;
%"Q_CAP"
"1","(-1700,3425)","2","pure_quanta","I61";
;
PACK_TYPE"0402"
MATERIAL"X7R"
TOLERANCE"10%"
VOLTAGE"25V"
VALUE"0.1UF"
PART_NUMBER"CH4104K1B00"
CDS_LIB"pure_quanta"
$LOCATION"C301"
CDS_LOCATION"C301"
$SEC"1"
CDS_SEC"1";
"B"
$PN"2"10;
"A"
$PN"1"1;
%"74LVC1G08GW"
"1","(-2000,2950)","0","pure_quanta","I63";
;
MATERIAL"IC"
PACK_TYPE"SM"
VALUE"74LVC1G08GW"
PART_NUMBER"ALVC1G08009"
CDS_LIB"pure_quanta"
NEEDS_NO_SIZE"TRUE"
$LOCATION"U52"
CDS_LOCATION"U52"
$SEC"1"
CDS_SEC"1";
"VCC"
$PN"5"1;
"Y"
$PN"4"29;
"B"
$PN"1"28;
"A"
$PN"2"20;
"GND"
$PN"3"11;
%"Q_RES"
"1","(-1700,475)","0","pure_quanta","I68";
;
VALUE"0"
MATERIAL"EMPTY"
TOLERANCE"5%"
WATTAGE"1/16W"
PACK_TYPE"0402LF"
PART_NUMBER"CS00002JB13"
CDS_LIB"pure_quanta"
$LOCATION"R876"
CDS_LOCATION"R876"
$SEC"1"
CDS_SEC"1";
"B"
$PN"2"30;
"A"
$PN"1"24;
%"Q_CAP"
"1","(-3575,-225)","0","pure_quanta","I7";
;
VOLTAGE"25V"
PACK_TYPE"C0402"
TOLERANCE"10%"
VALUE"1UF"
PART_NUMBER"CH5104KEB02"
MATERIAL"X6S"
CDS_LIB"pure_quanta"
SEC_TYPE"C0402"
LOCATION"PC250"
SEC"1";
"B"
$PN"2"14;
"A"
$PN"1"23;
%"Q_RES"
"1","(1750,1325)","0","pure_quanta","I70";
;
PACK_TYPE"0402LF"
PART_NUMBER"CS00002JB13"
VALUE"0"
MATERIAL"EMPTY"
CDS_LIB"pure_quanta"
WATTAGE"1/16W"
TOLERANCE"5%"
$LOCATION"R877"
CDS_LOCATION"R877"
$SEC"1"
CDS_SEC"1";
"B"
$PN"2"21;
"A"
$PN"1"32;
%"UNIVERSAL_POWER"
"1","(-1700,3625)","0","logical_power","I72";
;
HDL_POWER"P3V3_LDO"
CDS_LIB"logical_power";
"A"1;
%"Q_RES"
"2","(-3575,300)","0","pure_quanta","I8";
;
VALUE"5.1"
TOLERANCE"5%"
WATTAGE"1/16W"
MATERIAL"CHIP"
PACK_TYPE"0402LF"
PART_NUMBER"CS-5102JB02"
CDS_LIB"pure_quanta"
LOCATION"PR539"
$SEC"1"
CDS_SEC"1";
"A"
$PN"1"3;
"B"
$PN"2"23;
%"VCCAUX15"
"1","(-3575,500)","0","logical_power","I9";
;
HDL_POWER"PVCC1_AUX"
CDS_LIB"logical_power";
"A"3;
END.
